(kicad_pcb
	(version 20260206)
	(generator "pcbnew")
	(generator_version "10.0")
	(general
		(thickness 1.6)
		(legacy_teardrops no)
	)
	(paper "A4")
	(title_block
		(title "timecard-production-celestica-r4006 — R4006-B0001-02_R01.brd")
		(comment 1 "Time Appliance Project (Time Card) / footprints 325-327 of 1113")
	)
	(layers
		(0 "F.Cu" signal "TOP")
		(4 "In1.Cu" signal "L02_GND1")
		(6 "In2.Cu" signal "L03_SIG1")
		(8 "In3.Cu" signal "L04_GND2")
		(10 "In4.Cu" signal "L05_VCC1")
		(12 "In5.Cu" signal "L06_VCC2")
		(14 "In6.Cu" signal "L07_GND3")
		(16 "In7.Cu" signal "L08_SIG2")
		(18 "In8.Cu" signal "L09_GND4")
		(2 "B.Cu" signal "BOTTOM")
		(9 "F.Adhes" user "F.Adhesive")
		(11 "B.Adhes" user "B.Adhesive")
		(13 "F.Paste" user "Package Geometry/Pastemask Top")
		(15 "B.Paste" user "Package Geometry/Pastemask Bottom")
		(5 "F.SilkS" user "Ref Des/Silkscreen Top")
		(7 "B.SilkS" user "Ref Des/Silkscreen Bottom")
		(1 "F.Mask" user "Board Geometry/Soldermask Top")
		(3 "B.Mask" user "Board Geometry/Soldermask Bottom")
		(17 "Dwgs.User" user "User.Drawings")
		(19 "Cmts.User" user "User.Comments")
		(21 "Eco1.User" user "User.Eco1")
		(23 "Eco2.User" user "User.Eco2")
		(25 "Edge.Cuts" user "Board Geometry/Outline")
		(27 "Margin" user)
		(31 "F.CrtYd" user "Package Geometry/Place Bound Top")
		(29 "B.CrtYd" user "Package Geometry/Place Bound Bottom")
		(35 "F.Fab" user "Ref Des/Assembly Top")
		(33 "B.Fab" user "Ref Des/Assembly Bottom")
	)
	(footprint ""
		(layer "F.Cu")
		(at 159.255206 -57.361836 -90)
		(property "Reference" "U9"
			(at -3.812794 -0.129794 0)
			(unlocked yes)
			(layer "F.SilkS")
			(effects
				(font
					(size 0.7874 0.5842)
					(thickness 0.1524)
				)
			)
		)
		(property "Value" ""
			(at 0 0 270)
			(layer "F.Fab")
			(effects
				(font
					(size 1.27 1.27)
				)
			)
		)
		(property "User Part Number" "PARTNUM*"
			(at 0.1016 3.45567 270)
			(unlocked yes)
			(layer "Cmts.User")
			(hide yes)
			(effects
				(font
					(size 0.7874 0.5842)
					(thickness 0.1524)
				)
			)
		)
		(property "Device Type" "CL1001485A-G122-00019-01"
			(at 0.1016 2.54127 270)
			(unlocked yes)
			(layer "F.Fab")
			(hide yes)
			(effects
				(font
					(size 0.7874 0.5842)
					(thickness 0.1524)
				)
			)
		)
		(duplicate_pad_numbers_are_jumpers no)
		(fp_line
			(start -1.0541 1.704086)
			(end 1.0541 1.704086)
			(stroke
				(width 0.1)
				(type default)
			)
			(layer "F.SilkS")
		)
		(fp_line
			(start 1.0541 1.704086)
			(end 1.0541 1.45796)
			(stroke
				(width 0.1)
				(type default)
			)
			(layer "F.SilkS")
		)
		(fp_line
			(start -2.286 1.45796)
			(end -1.0541 1.45796)
			(stroke
				(width 0.1)
				(type default)
			)
			(layer "F.SilkS")
		)
		(fp_line
			(start -1.0541 1.45796)
			(end -1.0541 1.704086)
			(stroke
				(width 0.1)
				(type default)
			)
			(layer "F.SilkS")
		)
		(fp_line
			(start 1.0541 1.45796)
			(end 2.286 1.45796)
			(stroke
				(width 0.1)
				(type default)
			)
			(layer "F.SilkS")
		)
		(fp_line
			(start 2.286 1.45796)
			(end 2.286 -1.45796)
			(stroke
				(width 0.1)
				(type default)
			)
			(layer "F.SilkS")
		)
		(fp_line
			(start -2.286 -1.45796)
			(end -2.286 1.45796)
			(stroke
				(width 0.1)
				(type default)
			)
			(layer "F.SilkS")
		)
		(fp_line
			(start -1.0541 -1.45796)
			(end -2.286 -1.45796)
			(stroke
				(width 0.1)
				(type default)
			)
			(layer "F.SilkS")
		)
		(fp_line
			(start 1.0541 -1.45796)
			(end 1.0541 -1.704086)
			(stroke
				(width 0.1)
				(type default)
			)
			(layer "F.SilkS")
		)
		(fp_line
			(start 2.286 -1.45796)
			(end 1.0541 -1.45796)
			(stroke
				(width 0.1)
				(type default)
			)
			(layer "F.SilkS")
		)
		(fp_line
			(start -1.0541 -1.704086)
			(end -1.0541 -1.45796)
			(stroke
				(width 0.1)
				(type default)
			)
			(layer "F.SilkS")
		)
		(fp_line
			(start 1.0541 -1.704086)
			(end -1.0541 -1.704086)
			(stroke
				(width 0.1)
				(type default)
			)
			(layer "F.SilkS")
		)
		(fp_poly
			(pts
				(arc
					(start -2.06756 -2.314194)
					(mid -2.06756 -1.552194)
					(end -2.06756 -2.314194)
				)
			)
			(stroke
				(width 0)
				(type default)
			)
			(fill yes)
			(layer "F.SilkS")
		)
		(fp_rect
			(start 2.54 1.9558)
			(end -2.54 -1.9558)
			(stroke
				(width 0)
				(type default)
			)
			(fill no)
			(layer "F.CrtYd")
		)
		(fp_line
			(start -0.8001 1.450086)
			(end 0.8001 1.450086)
			(stroke
				(width 0.1)
				(type default)
			)
			(layer "F.Fab")
		)
		(fp_line
			(start -0.8001 1.450086)
			(end -0.599948 1.249934)
			(stroke
				(width 0.1)
				(type default)
			)
			(layer "F.Fab")
		)
		(fp_line
			(start 0.8001 1.450086)
			(end 0.599948 1.249934)
			(stroke
				(width 0.1)
				(type default)
			)
			(layer "F.Fab")
		)
		(fp_line
			(start 0.8001 1.450086)
			(end 0.8001 1.199896)
			(stroke
				(width 0.1)
				(type default)
			)
			(layer "F.Fab")
		)
		(fp_line
			(start -0.599948 1.249934)
			(end -0.599948 -1.249934)
			(stroke
				(width 0.1)
				(type default)
			)
			(layer "F.Fab")
		)
		(fp_line
			(start 0.599948 1.249934)
			(end -0.599948 1.249934)
			(stroke
				(width 0.1)
				(type default)
			)
			(layer "F.Fab")
		)
		(fp_line
			(start -1.500124 1.199896)
			(end -1.500124 0.700024)
			(stroke
				(width 0.1)
				(type default)
			)
			(layer "F.Fab")
		)
		(fp_line
			(start -0.8001 1.199896)
			(end -0.8001 1.450086)
			(stroke
				(width 0.1)
				(type default)
			)
			(layer "F.Fab")
		)
		(fp_line
			(start -0.700024 1.199896)
			(end -1.500124 1.199896)
			(stroke
				(width 0.1)
				(type default)
			)
			(layer "F.Fab")
		)
		(fp_line
			(start 0.700024 1.199896)
			(end 0.700024 0.700024)
			(stroke
				(width 0.1)
				(type default)
			)
			(layer "F.Fab")
		)
		(fp_line
			(start 1.500124 1.199896)
			(end 0.700024 1.199896)
			(stroke
				(width 0.1)
				(type default)
			)
			(layer "F.Fab")
		)
		(fp_line
			(start -1.500124 0.700024)
			(end -0.700024 0.700024)
			(stroke
				(width 0.1)
				(type default)
			)
			(layer "F.Fab")
		)
		(fp_line
			(start -0.700024 0.700024)
			(end -0.700024 1.199896)
			(stroke
				(width 0.1)
				(type default)
			)
			(layer "F.Fab")
		)
		(fp_line
			(start 0.700024 0.700024)
			(end 1.500124 0.700024)
			(stroke
				(width 0.1)
				(type default)
			)
			(layer "F.Fab")
		)
		(fp_line
			(start 1.500124 0.700024)
			(end 1.500124 1.199896)
			(stroke
				(width 0.1)
				(type default)
			)
			(layer "F.Fab")
		)
		(fp_line
			(start -1.500124 0.249936)
			(end -1.500124 -0.249936)
			(stroke
				(width 0.1)
				(type default)
			)
			(layer "F.Fab")
		)
		(fp_line
			(start -0.8001 0.249936)
			(end -0.8001 0.700024)
			(stroke
				(width 0.1)
				(type default)
			)
			(layer "F.Fab")
		)
		(fp_line
			(start -0.700024 0.249936)
			(end -1.500124 0.249936)
			(stroke
				(width 0.1)
				(type default)
			)
			(layer "F.Fab")
		)
		(fp_line
			(start 0.700024 0.249936)
			(end 0.8001 0.249936)
			(stroke
				(width 0.1)
				(type default)
			)
			(layer "F.Fab")
		)
		(fp_line
			(start 0.700024 0.249936)
			(end 0.700024 -0.249936)
			(stroke
				(width 0.1)
				(type default)
			)
			(layer "F.Fab")
		)
		(fp_line
			(start 0.8001 0.249936)
			(end 0.8001 0.700024)
			(stroke
				(width 0.1)
				(type default)
			)
			(layer "F.Fab")
		)
		(fp_line
			(start 1.500124 0.249936)
			(end 0.700024 0.249936)
			(stroke
				(width 0.1)
				(type default)
			)
			(layer "F.Fab")
		)
		(fp_line
			(start -1.500124 -0.249936)
			(end -0.700024 -0.249936)
			(stroke
				(width 0.1)
				(type default)
			)
			(layer "F.Fab")
		)
		(fp_line
			(start -0.700024 -0.249936)
			(end -0.700024 0.249936)
			(stroke
				(width 0.1)
				(type default)
			)
			(layer "F.Fab")
		)
		(fp_line
			(start 0.700024 -0.249936)
			(end 0.700024 0.249936)
			(stroke
				(width 0.1)
				(type default)
			)
			(layer "F.Fab")
		)
		(fp_line
			(start 0.700024 -0.249936)
			(end 1.500124 -0.249936)
			(stroke
				(width 0.1)
				(type default)
			)
			(layer "F.Fab")
		)
		(fp_line
			(start 0.8001 -0.249936)
			(end 0.700024 -0.249936)
			(stroke
				(width 0.1)
				(type default)
			)
			(layer "F.Fab")
		)
		(fp_line
			(start 1.500124 -0.249936)
			(end 1.500124 0.249936)
			(stroke
				(width 0.1)
				(type default)
			)
			(layer "F.Fab")
		)
		(fp_line
			(start -1.500124 -0.700024)
			(end -1.500124 -1.199896)
			(stroke
				(width 0.1)
				(type default)
			)
			(layer "F.Fab")
		)
		(fp_line
			(start -0.8001 -0.700024)
			(end -0.8001 -0.249936)
			(stroke
				(width 0.1)
				(type default)
			)
			(layer "F.Fab")
		)
		(fp_line
			(start -0.700024 -0.700024)
			(end -1.500124 -0.700024)
			(stroke
				(width 0.1)
				(type default)
			)
			(layer "F.Fab")
		)
		(fp_line
			(start 0.700024 -0.700024)
			(end 0.700024 -1.199896)
			(stroke
				(width 0.1)
				(type default)
			)
			(layer "F.Fab")
		)
		(fp_line
			(start 0.8001 -0.700024)
			(end 0.8001 -0.249936)
			(stroke
				(width 0.1)
				(type default)
			)
			(layer "F.Fab")
		)
		(fp_line
			(start 1.500124 -0.700024)
			(end 0.700024 -0.700024)
			(stroke
				(width 0.1)
				(type default)
			)
			(layer "F.Fab")
		)
		(fp_line
			(start -1.500124 -1.199896)
			(end -0.700024 -1.199896)
			(stroke
				(width 0.1)
				(type default)
			)
			(layer "F.Fab")
		)
		(fp_line
			(start -0.8001 -1.199896)
			(end -0.8001 -1.450086)
			(stroke
				(width 0.1)
				(type default)
			)
			(layer "F.Fab")
		)
		(fp_line
			(start -0.700024 -1.199896)
			(end -0.700024 -0.700024)
			(stroke
				(width 0.1)
				(type default)
			)
			(layer "F.Fab")
		)
		(fp_line
			(start 0.700024 -1.199896)
			(end 1.500124 -1.199896)
			(stroke
				(width 0.1)
				(type default)
			)
			(layer "F.Fab")
		)
		(fp_line
			(start 1.500124 -1.199896)
			(end 1.500124 -0.700024)
			(stroke
				(width 0.1)
				(type default)
			)
			(layer "F.Fab")
		)
		(fp_line
			(start -0.599948 -1.249934)
			(end 0.599948 -1.249934)
			(stroke
				(width 0.1)
				(type default)
			)
			(layer "F.Fab")
		)
		(fp_line
			(start -0.599948 -1.249934)
			(end -0.8001 -1.450086)
			(stroke
				(width 0.1)
				(type default)
			)
			(layer "F.Fab")
		)
		(fp_line
			(start 0.599948 -1.249934)
			(end 0.599948 1.249934)
			(stroke
				(width 0.1)
				(type default)
			)
			(layer "F.Fab")
		)
		(fp_line
			(start 0.599948 -1.249934)
			(end 0.8001 -1.450086)
			(stroke
				(width 0.1)
				(type default)
			)
			(layer "F.Fab")
		)
		(fp_line
			(start -0.8001 -1.450086)
			(end 0.8001 -1.450086)
			(stroke
				(width 0.1)
				(type default)
			)
			(layer "F.Fab")
		)
		(fp_line
			(start 0.8001 -1.450086)
			(end 0.8001 -1.199896)
			(stroke
				(width 0.1)
				(type default)
			)
			(layer "F.Fab")
		)
		(fp_poly
			(pts
				(arc
					(start -0.350012 -1.100074)
					(mid -0.350012 -0.799846)
					(end -0.350012 -1.100074)
				)
			)
			(stroke
				(width 0)
				(type default)
			)
			(fill yes)
			(layer "F.Fab")
		)
		(fp_text user "3"
			(at -2.25679 2.029206 0)
			(unlocked yes)
			(layer "F.SilkS")
			(effects
				(font
					(size 0.7874 0.5842)
					(thickness 0.1524)
				)
			)
		)
		(fp_text user "4"
			(at 3.07721 1.394206 0)
			(unlocked yes)
			(layer "F.SilkS")
			(effects
				(font
					(size 0.7874 0.5842)
					(thickness 0.1524)
				)
			)
		)
		(fp_text user "6"
			(at 3.045206 -1.145794 0)
			(unlocked yes)
			(layer "F.SilkS")
			(effects
				(font
					(size 0.7874 0.5842)
					(thickness 0.1524)
				)
			)
		)
		(fp_text user "3"
			(at -2.52349 1.140206 0)
			(unlocked yes)
			(layer "F.Fab")
			(effects
				(font
					(size 0.7874 0.5842)
					(thickness 0.1524)
				)
			)
		)
		(fp_text user "4"
			(at 2.43967 0.9906 0)
			(unlocked yes)
			(layer "F.Fab")
			(effects
				(font
					(size 0.7874 0.5842)
					(thickness 0.1524)
				)
			)
		)
		(fp_text user "6"
			(at 2.38887 -0.9398 0)
			(unlocked yes)
			(layer "F.Fab")
			(effects
				(font
					(size 0.7874 0.5842)
					(thickness 0.1524)
				)
			)
		)
		(pad "1" smd rect
			(at -1.4351 -0.94996)
			(size 0.508 1.1938)
			(layers "F.Cu" "F.Mask" "F.Paste")
			(net "Net_758")
		)
		(pad "2" smd rect
			(at -1.4351 0)
			(size 0.508 1.1938)
			(layers "F.Cu" "F.Mask" "F.Paste")
			(net "SG")
		)
		(pad "3" smd rect
			(at -1.4351 0.94996)
			(size 0.508 1.1938)
			(layers "F.Cu" "F.Mask" "F.Paste")
			(net "Net_757")
		)
		(pad "4" smd rect
			(at 1.4351 0.94996)
			(size 0.508 1.1938)
			(layers "F.Cu" "F.Mask" "F.Paste")
			(net "CONN_MICRO_USB_DM")
		)
		(pad "5" smd rect
			(at 1.4351 0)
			(size 0.508 1.1938)
			(layers "F.Cu" "F.Mask" "F.Paste")
			(net "XP5R0V_USB_CONN")
		)
		(pad "6" smd rect
			(at 1.4351 -0.94996)
			(size 0.508 1.1938)
			(layers "F.Cu" "F.Mask" "F.Paste")
			(net "CONN_MICRO_USB_DP")
		)
	)
	(footprint ""
		(layer "F.Cu")
		(at 68.216018 -28.484322)
		(property "Reference" "ME8"
			(at 3.157982 -3.607308 0)
			(unlocked yes)
			(layer "F.SilkS")
			(effects
				(font
					(size 0.7874 0.5842)
					(thickness 0.1524)
				)
			)
		)
		(property "Value" ""
			(at 0 0 0)
			(layer "F.Fab")
			(effects
				(font
					(size 1.27 1.27)
				)
			)
		)
		(duplicate_pad_numbers_are_jumpers no)
		(fp_poly
			(pts
				(arc
					(start 3.556 0)
					(mid -3.556 0)
					(end 3.556 0)
				)
			)
			(stroke
				(width 0)
				(type default)
			)
			(fill no)
			(layer "B.CrtYd")
		)
		(fp_poly
			(pts
				(arc
					(start 3.556 0)
					(mid -3.556 0)
					(end 3.556 0)
				)
			)
			(stroke
				(width 0)
				(type default)
			)
			(fill no)
			(layer "F.CrtYd")
		)
		(fp_circle
			(center 0 0)
			(end 3.048 0)
			(stroke
				(width 0.1)
				(type default)
			)
			(fill no)
			(layer "B.Fab")
		)
		(fp_circle
			(center 0 0)
			(end 3.048 0)
			(stroke
				(width 0.1)
				(type default)
			)
			(fill no)
			(layer "F.Fab")
		)
		(pad "" np_thru_hole circle
			(at 0 0)
			(size 2.286 2.286)
			(drill 2.54)
			(layers "*.Cu" "*.Mask")
			(padstack
				(mode front_inner_back)
				(layer "Inner"
					(shape circle)
					(size 2.286 2.286)
					(clearance 0.4445)
				)
				(layer "B.Cu"
					(shape circle)
					(size 2.286 2.286)
				)
			)
		)
		(zone
			(layers "F.Cu" "B.Cu" "In1.Cu" "In2.Cu" "In3.Cu" "In4.Cu" "In5.Cu" "In6.Cu"
				"In7.Cu" "In8.Cu"
			)
			(hatch none 0.5)
			(connect_pads
				(clearance 0)
			)
			(min_thickness 0.25)
			(keepout
				(tracks not_allowed)
				(vias allowed)
				(pads allowed)
				(copperpour not_allowed)
				(footprints allowed)
			)
			(placement
				(enabled no)
				(sheetname "")
			)
			(fill
				(thermal_gap 0.5)
				(thermal_bridge_width 0.5)
				(island_removal_mode 0)
			)
			(polygon
				(pts
					(arc
						(start 69.790818 -28.484322)
						(mid 66.641218 -28.484322)
						(end 69.790818 -28.484322)
					)
				)
			)
		)
	)
	(footprint ""
		(layer "F.Cu")
		(at 156.04998 -104.350058 -90)
		(property "Reference" "DS12"
			(at 0.591058 -2.23139 90)
			(unlocked yes)
			(layer "F.SilkS")
			(effects
				(font
					(size 0.7874 0.5842)
					(thickness 0.1524)
				)
			)
		)
		(property "Value" ""
			(at 0 0 270)
			(layer "F.Fab")
			(effects
				(font
					(size 1.27 1.27)
				)
			)
		)
		(property "Device Type" "OPTICAL-G170-10143-01"
			(at 0.1778 1.483081 270)
			(unlocked yes)
			(layer "F.Fab")
			(hide yes)
			(effects
				(font
					(size 0.786892 0.583946)
					(thickness 0.000001)
				)
			)
		)
		(property "User Part Number" "PARTNUM*"
			(at 0.1778 2.422881 270)
			(unlocked yes)
			(layer "Cmts.User")
			(hide yes)
			(effects
				(font
					(size 0.786892 0.583946)
					(thickness 0.000001)
				)
			)
		)
		(duplicate_pad_numbers_are_jumpers no)
		(fp_line
			(start -0.9398 1.4732)
			(end -2.2098 1.4732)
			(stroke
				(width 0.1)
				(type default)
			)
			(layer "F.SilkS")
		)
		(fp_line
			(start -1.5748 0.8382)
			(end -1.5748 2.1082)
			(stroke
				(width 0.1)
				(type default)
			)
			(layer "F.SilkS")
		)
		(fp_line
			(start -1.397508 0.704088)
			(end -1.397508 -0.704088)
			(stroke
				(width 0.1)
				(type default)
			)
			(layer "F.SilkS")
		)
		(fp_line
			(start 1.397508 0.704088)
			(end -1.397508 0.704088)
			(stroke
				(width 0.1)
				(type default)
			)
			(layer "F.SilkS")
		)
		(fp_line
			(start -1.397508 -0.704088)
			(end 1.397508 -0.704088)
			(stroke
				(width 0.1)
				(type default)
			)
			(layer "F.SilkS")
		)
		(fp_line
			(start 1.397508 -0.704088)
			(end 1.397508 0.704088)
			(stroke
				(width 0.1)
				(type default)
			)
			(layer "F.SilkS")
		)
		(fp_poly
			(pts
				(xy 1.397508 0.704088) (xy 1.397508 -0.704088) (xy 1.905508 -0.704088) (xy 1.905508 0.704088)
			)
			(stroke
				(width 0)
				(type default)
			)
			(fill yes)
			(layer "F.SilkS")
		)
		(fp_poly
			(pts
				(xy -1.651508 0.958088) (xy 1.905508 0.958088) (xy 1.905508 -0.958088) (xy -1.651508 -0.958088)
			)
			(stroke
				(width 0)
				(type default)
			)
			(fill no)
			(layer "F.CrtYd")
		)
		(fp_line
			(start -0.9398 1.3462)
			(end -2.2098 1.3462)
			(stroke
				(width 0.1)
				(type default)
			)
			(layer "F.Fab")
		)
		(fp_line
			(start -1.5748 0.7112)
			(end -1.5748 1.9812)
			(stroke
				(width 0.1)
				(type default)
			)
			(layer "F.Fab")
		)
		(fp_line
			(start -0.850138 0.450088)
			(end 0.850138 0.450088)
			(stroke
				(width 0.1)
				(type default)
			)
			(layer "F.Fab")
		)
		(fp_line
			(start 0.850138 0.450088)
			(end 0.850138 -0.450088)
			(stroke
				(width 0.1)
				(type default)
			)
			(layer "F.Fab")
		)
		(fp_line
			(start -0.850138 -0.450088)
			(end -0.850138 0.450088)
			(stroke
				(width 0.1)
				(type default)
			)
			(layer "F.Fab")
		)
		(fp_line
			(start 0.850138 -0.450088)
			(end -0.850138 -0.450088)
			(stroke
				(width 0.1)
				(type default)
			)
			(layer "F.Fab")
		)
		(fp_poly
			(pts
				(xy 0.850138 -0.450088) (xy 0.850138 0.450088) (xy 0.342138 0.450088) (xy 0.342138 -0.450088)
			)
			(stroke
				(width 0)
				(type default)
			)
			(fill yes)
			(layer "F.Fab")
		)
		(fp_text user "C"
			(at 2.400808 -1.04902 0)
			(unlocked yes)
			(layer "F.SilkS")
			(effects
				(font
					(size 0.635 0.4064)
					(thickness 0.1524)
				)
			)
		)
		(fp_text user "A"
			(at -0.901192 -1.17602 0)
			(unlocked yes)
			(layer "F.SilkS")
			(effects
				(font
					(size 0.635 0.4064)
					(thickness 0.1524)
				)
			)
		)
		(fp_text user "A"
			(at -0.893572 0.85598 0)
			(unlocked yes)
			(layer "F.Fab")
			(effects
				(font
					(size 0.7874 0.5842)
					(thickness 0.1524)
				)
			)
		)
		(fp_text user "C"
			(at 1.900428 -1.30302 0)
			(unlocked yes)
			(layer "F.Fab")
			(effects
				(font
					(size 0.7874 0.5842)
					(thickness 0.1524)
				)
			)
		)
		(pad "A" smd rect
			(at -0.749808 0 270)
			(size 0.7874 0.7874)
			(layers "F.Cu" "F.Mask" "F.Paste")
			(net "UNNAMED_14_OPTICAL_I289_A")
		)
		(pad "C" smd rect
			(at 0.749808 0 270)
			(size 0.7874 0.7874)
			(layers "F.Cu" "F.Mask" "F.Paste")
			(net "SG")
		)
	)
)
